(kicad_pcb
	(version 20260206)
	(generator "pcbnew")
	(generator_version "10.0")
	(general
		(thickness 1.6)
		(legacy_teardrops no)
	)
	(paper "A4")
	(title_block
		(title "03242023_DA0F0TMBIJ0_F0T_Motherboard_J_brd_V01_OCP.brd")
		(comment 1 "Grand Teton / footprints 5199-5204 of 6105")
	)
	(layers
		(0 "F.Cu" signal "TOP")
		(4 "In1.Cu" signal "GND")
		(6 "In2.Cu" signal "IN1")
		(8 "In3.Cu" signal "GND1")
		(10 "In4.Cu" signal "IN2")
		(12 "In5.Cu" signal "GND2")
		(14 "In6.Cu" signal "IN3")
		(16 "In7.Cu" signal "GND3")
		(18 "In8.Cu" signal "VCC")
		(20 "In9.Cu" signal "VCC1")
		(22 "In10.Cu" signal "GND4")
		(24 "In11.Cu" signal "IN4")
		(26 "In12.Cu" signal "GND5")
		(28 "In13.Cu" signal "IN5")
		(30 "In14.Cu" signal "GND6")
		(32 "In15.Cu" signal "IN6")
		(34 "In16.Cu" signal "GND7")
		(2 "B.Cu" signal "BOTTOM")
		(9 "F.Adhes" user "F.Adhesive")
		(11 "B.Adhes" user "B.Adhesive")
		(13 "F.Paste" user "Package Geometry/Pastemask Top")
		(15 "B.Paste" user "Package Geometry/Pastemask Bottom")
		(5 "F.SilkS" user "Ref Des/Silkscreen Top")
		(7 "B.SilkS" user "Ref Des/Silkscreen Bottom")
		(1 "F.Mask" user "Board Geometry/Soldermask Top")
		(3 "B.Mask" user "Board Geometry/Soldermask Bottom")
		(17 "Dwgs.User" user "User.Drawings")
		(19 "Cmts.User" user "User.Comments")
		(21 "Eco1.User" user "User.Eco1")
		(23 "Eco2.User" user "User.Eco2")
		(25 "Edge.Cuts" user "Board Geometry/Outline")
		(27 "Margin" user)
		(31 "F.CrtYd" user "Package Geometry/Place Bound Top")
		(29 "B.CrtYd" user "Package Geometry/Place Bound Bottom")
		(35 "F.Fab" user "Ref Des/Assembly Top")
		(33 "B.Fab" user "Ref Des/Assembly Bottom")
	)
	(footprint ""
		(layer "B.Cu")
		(at 413.6644 -363.125258 -90)
		(property "Reference" "PR355"
			(at 0 0 90)
			(layer "B.SilkS")
			(hide yes)
			(effects
				(font
					(size 1.27 1.27)
				)
				(justify mirror)
			)
		)
		(property "Value" ""
			(at 0 0 90)
			(layer "B.Fab")
			(effects
				(font
					(size 1.27 1.27)
				)
				(justify mirror)
			)
		)
		(duplicate_pad_numbers_are_jumpers no)
		(fp_line
			(start -0.7874 0.4064)
			(end 0.7874 0.4064)
			(stroke
				(width 0.1524)
				(type default)
			)
			(layer "B.SilkS")
		)
		(fp_line
			(start 0.7874 0.4064)
			(end 0.7874 -0.4064)
			(stroke
				(width 0.1524)
				(type default)
			)
			(layer "B.SilkS")
		)
		(fp_line
			(start -0.7874 -0.4064)
			(end -0.7874 0.4064)
			(stroke
				(width 0.1524)
				(type default)
			)
			(layer "B.SilkS")
		)
		(fp_line
			(start 0.7874 -0.4064)
			(end -0.7874 -0.4064)
			(stroke
				(width 0.1524)
				(type default)
			)
			(layer "B.SilkS")
		)
		(fp_line
			(start -0.67945 0.3048)
			(end -0.120396 0.3048)
			(stroke
				(width 0.1)
				(type default)
			)
			(layer "B.Fab")
		)
		(fp_line
			(start -0.120396 0.3048)
			(end -0.120396 0.2794)
			(stroke
				(width 0.1)
				(type default)
			)
			(layer "B.Fab")
		)
		(fp_line
			(start 0.12065 0.3048)
			(end 0.67945 0.3048)
			(stroke
				(width 0.1)
				(type default)
			)
			(layer "B.Fab")
		)
		(fp_line
			(start 0.67945 0.3048)
			(end 0.67945 -0.305054)
			(stroke
				(width 0.1)
				(type default)
			)
			(layer "B.Fab")
		)
		(fp_line
			(start -0.120396 0.2794)
			(end 0.12065 0.2794)
			(stroke
				(width 0.1)
				(type default)
			)
			(layer "B.Fab")
		)
		(fp_line
			(start 0.12065 0.2794)
			(end 0.12065 0.3048)
			(stroke
				(width 0.1)
				(type default)
			)
			(layer "B.Fab")
		)
		(fp_line
			(start -0.12065 -0.2794)
			(end -0.12065 -0.3048)
			(stroke
				(width 0.1)
				(type default)
			)
			(layer "B.Fab")
		)
		(fp_line
			(start 0.12065 -0.2794)
			(end -0.12065 -0.2794)
			(stroke
				(width 0.1)
				(type default)
			)
			(layer "B.Fab")
		)
		(fp_line
			(start -0.67945 -0.3048)
			(end -0.67945 0.3048)
			(stroke
				(width 0.1)
				(type default)
			)
			(layer "B.Fab")
		)
		(fp_line
			(start -0.12065 -0.3048)
			(end -0.67945 -0.3048)
			(stroke
				(width 0.1)
				(type default)
			)
			(layer "B.Fab")
		)
		(fp_line
			(start 0.12065 -0.305054)
			(end 0.12065 -0.2794)
			(stroke
				(width 0.1)
				(type default)
			)
			(layer "B.Fab")
		)
		(fp_line
			(start 0.67945 -0.305054)
			(end 0.12065 -0.305054)
			(stroke
				(width 0.1)
				(type default)
			)
			(layer "B.Fab")
		)
		(pad "1" smd circle
			(at 0.40005 0 90)
			(size 0 0)
			(layers "B.Cu" "B.Mask" "B.Paste")
			(net "PVCCFA_EHV_FIVRA_CPU0_PVCC1")
		)
		(pad "2" smd circle
			(at -0.40005 0 90)
			(size 0 0)
			(layers "B.Cu" "B.Mask" "B.Paste")
			(net "PVCCFA_EHV_FIVRA_CPU0_VDD1")
		)
	)
	(footprint ""
		(layer "B.Cu")
		(at 206.955898 -193.37401)
		(property "Reference" "U21"
			(at 0.22606 1.93167 0)
			(unlocked yes)
			(layer "B.SilkS")
			(effects
				(font
					(size 0.7874 0.5842)
					(thickness 0.1524)
				)
				(justify mirror)
			)
		)
		(property "Value" ""
			(at 0 0 0)
			(layer "B.Fab")
			(effects
				(font
					(size 1.27 1.27)
				)
				(justify mirror)
			)
		)
		(duplicate_pad_numbers_are_jumpers no)
		(fp_line
			(start -1.7272 -1.1176)
			(end -1.7272 1.1176)
			(stroke
				(width 0.1524)
				(type default)
			)
			(layer "B.SilkS")
		)
		(fp_line
			(start -1.7272 -1.1176)
			(end -0.254 -1.1176)
			(stroke
				(width 0.1524)
				(type default)
			)
			(layer "B.SilkS")
		)
		(fp_line
			(start -1.7272 1.1176)
			(end 1.7272 1.1176)
			(stroke
				(width 0.1524)
				(type default)
			)
			(layer "B.SilkS")
		)
		(fp_line
			(start -0.254 -1.1176)
			(end 0 -0.7366)
			(stroke
				(width 0.1524)
				(type default)
			)
			(layer "B.SilkS")
		)
		(fp_line
			(start 0 -0.7366)
			(end 0.254 -1.1176)
			(stroke
				(width 0.1524)
				(type default)
			)
			(layer "B.SilkS")
		)
		(fp_line
			(start 0.254 -1.1176)
			(end 1.7272 -1.1176)
			(stroke
				(width 0.1524)
				(type default)
			)
			(layer "B.SilkS")
		)
		(fp_line
			(start 1.7272 1.1176)
			(end 1.7272 -1.1176)
			(stroke
				(width 0.1524)
				(type default)
			)
			(layer "B.SilkS")
		)
		(fp_poly
			(pts
				(xy 1.064514 -1.395476) (xy 0.683514 -2.157476) (xy 1.445514 -2.157476)
			)
			(stroke
				(width 0)
				(type default)
			)
			(fill yes)
			(layer "B.SilkS")
		)
		(fp_line
			(start -1.5748 -1.1176)
			(end 1.5748 -1.1176)
			(stroke
				(width 0.1)
				(type default)
			)
			(layer "B.Fab")
		)
		(fp_line
			(start -1.5748 1.1176)
			(end -1.5748 -1.1176)
			(stroke
				(width 0.1)
				(type default)
			)
			(layer "B.Fab")
		)
		(fp_line
			(start 1.5748 -1.1176)
			(end 1.5748 1.1176)
			(stroke
				(width 0.1)
				(type default)
			)
			(layer "B.Fab")
		)
		(fp_line
			(start 1.5748 1.1176)
			(end -1.5748 1.1176)
			(stroke
				(width 0.1)
				(type default)
			)
			(layer "B.Fab")
		)
		(fp_poly
			(pts
				(xy 1.9558 -0.649986) (xy 2.7178 -0.268986) (xy 2.7178 -1.030986)
			)
			(stroke
				(width 0)
				(type default)
			)
			(fill yes)
			(layer "B.Fab")
		)
		(pad "1" smd rect
			(at 0.999998 -0.649986 270)
			(size 0.3556 1.1176)
			(layers "B.Cu" "B.Mask" "B.Paste")
			(net "JTAG_MUX_CPU1_GTL_TDI")
		)
		(pad "2" smd rect
			(at 0.999998 0 270)
			(size 0.3556 1.1176)
			(layers "B.Cu" "B.Mask" "B.Paste")
			(net "GND")
		)
		(pad "3" smd rect
			(at 0.999998 0.649986 270)
			(size 0.3556 1.1176)
			(layers "B.Cu" "B.Mask" "B.Paste")
			(net "JTAG_MUX_CPU0_GTL_TDI")
		)
		(pad "4" smd rect
			(at -0.999998 0.649986 270)
			(size 0.3556 1.1176)
			(layers "B.Cu" "B.Mask" "B.Paste")
			(net "JTAG_QS_MUX_GTL_TDI")
		)
		(pad "5" smd rect
			(at -0.999998 0 270)
			(size 0.3556 1.1176)
			(layers "B.Cu" "B.Mask" "B.Paste")
			(net "P3V3_AUX")
		)
		(pad "6" smd rect
			(at -0.999998 -0.649986 270)
			(size 0.3556 1.1176)
			(layers "B.Cu" "B.Mask" "B.Paste")
			(net "FM_CPU0_SKTOCC_N")
		)
	)
	(footprint ""
		(layer "B.Cu")
		(at 106.661712 -337.607402 -90)
		(property "Reference" "PC568_P1_2"
			(at 0 0 90)
			(layer "B.SilkS")
			(hide yes)
			(effects
				(font
					(size 1.27 1.27)
				)
				(justify mirror)
			)
		)
		(property "Value" ""
			(at 0 0 90)
			(layer "B.Fab")
			(effects
				(font
					(size 1.27 1.27)
				)
				(justify mirror)
			)
		)
		(duplicate_pad_numbers_are_jumpers no)
		(fp_line
			(start -1.524 0.762)
			(end 1.524 0.762)
			(stroke
				(width 0.1524)
				(type default)
			)
			(layer "B.SilkS")
		)
		(fp_line
			(start 1.524 0.762)
			(end 1.524 -0.762)
			(stroke
				(width 0.1524)
				(type default)
			)
			(layer "B.SilkS")
		)
		(fp_line
			(start -1.524 -0.762)
			(end -1.524 0.762)
			(stroke
				(width 0.1524)
				(type default)
			)
			(layer "B.SilkS")
		)
		(fp_line
			(start 1.524 -0.762)
			(end -1.524 -0.762)
			(stroke
				(width 0.1524)
				(type default)
			)
			(layer "B.SilkS")
		)
		(fp_line
			(start -1.1049 0.724916)
			(end -1.1049 -0.724916)
			(stroke
				(width 0.1)
				(type default)
			)
			(layer "B.Fab")
		)
		(fp_line
			(start 1.1049 0.724916)
			(end -1.1049 0.724916)
			(stroke
				(width 0.1)
				(type default)
			)
			(layer "B.Fab")
		)
		(fp_line
			(start -1.1049 -0.724916)
			(end 1.1049 -0.724916)
			(stroke
				(width 0.1)
				(type default)
			)
			(layer "B.Fab")
		)
		(fp_line
			(start 1.1049 -0.724916)
			(end 1.1049 0.724916)
			(stroke
				(width 0.1)
				(type default)
			)
			(layer "B.Fab")
		)
		(pad "1" smd rect
			(at 0.889 0 270)
			(size 1.016 1.27)
			(layers "B.Cu" "B.Mask" "B.Paste")
			(net "SW_P12V_PVCCIN_CPU1_FLT")
		)
		(pad "2" smd rect
			(at -0.889 0 270)
			(size 1.016 1.27)
			(layers "B.Cu" "B.Mask" "B.Paste")
			(net "GND")
		)
	)
	(footprint ""
		(layer "B.Cu")
		(at 329.646534 -25.803352 -90)
		(property "Reference" "R1310"
			(at 0 0 90)
			(layer "B.SilkS")
			(hide yes)
			(effects
				(font
					(size 1.27 1.27)
				)
				(justify mirror)
			)
		)
		(property "Value" ""
			(at 0 0 90)
			(layer "B.Fab")
			(effects
				(font
					(size 1.27 1.27)
				)
				(justify mirror)
			)
		)
		(duplicate_pad_numbers_are_jumpers no)
		(fp_line
			(start -0.7874 0.4064)
			(end 0.7874 0.4064)
			(stroke
				(width 0.1524)
				(type default)
			)
			(layer "B.SilkS")
		)
		(fp_line
			(start 0.7874 0.4064)
			(end 0.7874 -0.4064)
			(stroke
				(width 0.1524)
				(type default)
			)
			(layer "B.SilkS")
		)
		(fp_line
			(start -0.7874 -0.4064)
			(end -0.7874 0.4064)
			(stroke
				(width 0.1524)
				(type default)
			)
			(layer "B.SilkS")
		)
		(fp_line
			(start 0.7874 -0.4064)
			(end -0.7874 -0.4064)
			(stroke
				(width 0.1524)
				(type default)
			)
			(layer "B.SilkS")
		)
		(fp_line
			(start -0.67945 0.3048)
			(end -0.120396 0.3048)
			(stroke
				(width 0.1)
				(type default)
			)
			(layer "B.Fab")
		)
		(fp_line
			(start -0.120396 0.3048)
			(end -0.120396 0.2794)
			(stroke
				(width 0.1)
				(type default)
			)
			(layer "B.Fab")
		)
		(fp_line
			(start 0.12065 0.3048)
			(end 0.67945 0.3048)
			(stroke
				(width 0.1)
				(type default)
			)
			(layer "B.Fab")
		)
		(fp_line
			(start 0.67945 0.3048)
			(end 0.67945 -0.305054)
			(stroke
				(width 0.1)
				(type default)
			)
			(layer "B.Fab")
		)
		(fp_line
			(start -0.120396 0.2794)
			(end 0.12065 0.2794)
			(stroke
				(width 0.1)
				(type default)
			)
			(layer "B.Fab")
		)
		(fp_line
			(start 0.12065 0.2794)
			(end 0.12065 0.3048)
			(stroke
				(width 0.1)
				(type default)
			)
			(layer "B.Fab")
		)
		(fp_line
			(start -0.12065 -0.2794)
			(end -0.12065 -0.3048)
			(stroke
				(width 0.1)
				(type default)
			)
			(layer "B.Fab")
		)
		(fp_line
			(start 0.12065 -0.2794)
			(end -0.12065 -0.2794)
			(stroke
				(width 0.1)
				(type default)
			)
			(layer "B.Fab")
		)
		(fp_line
			(start -0.67945 -0.3048)
			(end -0.67945 0.3048)
			(stroke
				(width 0.1)
				(type default)
			)
			(layer "B.Fab")
		)
		(fp_line
			(start -0.12065 -0.3048)
			(end -0.67945 -0.3048)
			(stroke
				(width 0.1)
				(type default)
			)
			(layer "B.Fab")
		)
		(fp_line
			(start 0.12065 -0.305054)
			(end 0.12065 -0.2794)
			(stroke
				(width 0.1)
				(type default)
			)
			(layer "B.Fab")
		)
		(fp_line
			(start 0.67945 -0.305054)
			(end 0.12065 -0.305054)
			(stroke
				(width 0.1)
				(type default)
			)
			(layer "B.Fab")
		)
		(pad "1" smd circle
			(at 0.40005 0 90)
			(size 0 0)
			(layers "B.Cu" "B.Mask" "B.Paste")
			(net "IRQ_PCH_CPU_NMI_EVENT_R_N")
		)
		(pad "2" smd circle
			(at -0.40005 0 90)
			(size 0 0)
			(layers "B.Cu" "B.Mask" "B.Paste")
			(net "IRQ_PCH_CPU_NMI_EVENT_N")
		)
	)
	(footprint ""
		(layer "B.Cu")
		(at 353.535742 -262.348726)
		(property "Reference" "C356"
			(at 0 0 0)
			(layer "B.SilkS")
			(hide yes)
			(effects
				(font
					(size 1.27 1.27)
				)
				(justify mirror)
			)
		)
		(property "Value" ""
			(at 0 0 0)
			(layer "B.Fab")
			(effects
				(font
					(size 1.27 1.27)
				)
				(justify mirror)
			)
		)
		(duplicate_pad_numbers_are_jumpers no)
		(fp_line
			(start -1.524 -0.762)
			(end -1.524 0.762)
			(stroke
				(width 0.1524)
				(type default)
			)
			(layer "B.SilkS")
		)
		(fp_line
			(start -1.524 0.762)
			(end 1.524 0.762)
			(stroke
				(width 0.1524)
				(type default)
			)
			(layer "B.SilkS")
		)
		(fp_line
			(start 1.524 -0.762)
			(end -1.524 -0.762)
			(stroke
				(width 0.1524)
				(type default)
			)
			(layer "B.SilkS")
		)
		(fp_line
			(start 1.524 0.762)
			(end 1.524 -0.762)
			(stroke
				(width 0.1524)
				(type default)
			)
			(layer "B.SilkS")
		)
		(fp_line
			(start -1.1049 -0.724916)
			(end 1.1049 -0.724916)
			(stroke
				(width 0.1)
				(type default)
			)
			(layer "B.Fab")
		)
		(fp_line
			(start -1.1049 0.724916)
			(end -1.1049 -0.724916)
			(stroke
				(width 0.1)
				(type default)
			)
			(layer "B.Fab")
		)
		(fp_line
			(start 1.1049 -0.724916)
			(end 1.1049 0.724916)
			(stroke
				(width 0.1)
				(type default)
			)
			(layer "B.Fab")
		)
		(fp_line
			(start 1.1049 0.724916)
			(end -1.1049 0.724916)
			(stroke
				(width 0.1)
				(type default)
			)
			(layer "B.Fab")
		)
		(pad "1" smd rect
			(at 0.889 0)
			(size 1.016 1.27)
			(layers "B.Cu" "B.Mask" "B.Paste")
			(net "PVCCIN_CPU0")
		)
		(pad "2" smd rect
			(at -0.889 0)
			(size 1.016 1.27)
			(layers "B.Cu" "B.Mask" "B.Paste")
			(net "GND")
		)
	)
	(footprint ""
		(layer "B.Cu")
		(at 95.614998 -324.753986 -90)
		(property "Reference" "PC576_P1_1"
			(at 0 0 90)
			(layer "B.SilkS")
			(hide yes)
			(effects
				(font
					(size 1.27 1.27)
				)
				(justify mirror)
			)
		)
		(property "Value" ""
			(at 0 0 90)
			(layer "B.Fab")
			(effects
				(font
					(size 1.27 1.27)
				)
				(justify mirror)
			)
		)
		(duplicate_pad_numbers_are_jumpers no)
		(fp_line
			(start -1.524 0.762)
			(end 1.524 0.762)
			(stroke
				(width 0.1524)
				(type default)
			)
			(layer "B.SilkS")
		)
		(fp_line
			(start 1.524 0.762)
			(end 1.524 -0.762)
			(stroke
				(width 0.1524)
				(type default)
			)
			(layer "B.SilkS")
		)
		(fp_line
			(start -1.524 -0.762)
			(end -1.524 0.762)
			(stroke
				(width 0.1524)
				(type default)
			)
			(layer "B.SilkS")
		)
		(fp_line
			(start 1.524 -0.762)
			(end -1.524 -0.762)
			(stroke
				(width 0.1524)
				(type default)
			)
			(layer "B.SilkS")
		)
		(fp_line
			(start -1.1049 0.724916)
			(end -1.1049 -0.724916)
			(stroke
				(width 0.1)
				(type default)
			)
			(layer "B.Fab")
		)
		(fp_line
			(start 1.1049 0.724916)
			(end -1.1049 0.724916)
			(stroke
				(width 0.1)
				(type default)
			)
			(layer "B.Fab")
		)
		(fp_line
			(start -1.1049 -0.724916)
			(end 1.1049 -0.724916)
			(stroke
				(width 0.1)
				(type default)
			)
			(layer "B.Fab")
		)
		(fp_line
			(start 1.1049 -0.724916)
			(end 1.1049 0.724916)
			(stroke
				(width 0.1)
				(type default)
			)
			(layer "B.Fab")
		)
		(pad "1" smd rect
			(at 0.889 0 270)
			(size 1.016 1.27)
			(layers "B.Cu" "B.Mask" "B.Paste")
			(net "PVCCIN_CPU1")
		)
		(pad "2" smd rect
			(at -0.889 0 270)
			(size 1.016 1.27)
			(layers "B.Cu" "B.Mask" "B.Paste")
			(net "GND")
		)
	)
)
